# BASEBOARD_FAB2 (Tioga Pass) — schematic netlist excerpt (pin names and nets, part order shuffled) for the footprints in the layout excerpt that follows; sources: Cadence DE-HDL packaged netlist, KiCad conversion of Wiwynn_Tioga_Pass_MB.brd

C2D26  CAP_A  22.0UF 4V 20% X6S  pkg 0603V  page 76 : A = PVCCIN_CPU1 ; B = GND
RF17  RES  1.0K 0.1% CHIP  pkg 0402  page 218 : A = VR_PVDDQ_DEF_AIREF1 ; B = ISENSE_PVDDQ_DEF_PH1_IMON
RT1  RES  0 5.0% CHIP  pkg 0603  page 202 : A = VR_PVCCIN_CPU0_PH1_BOOT ; B = VR_PVCCIN_CPU0_PH1_BOOT_R

(kicad_pcb
	(version 20260206)
	(generator "pcbnew")
	(generator_version "10.0")
	(general
		(thickness 1.6)
		(legacy_teardrops no)
	)
	(paper "A4")
	(title_block
		(title "Wiwynn_Tioga_Pass_MB.brd")
		(comment 1 "Tioga Pass / footprints 98-100 of 4770")
	)
	(layers
		(0 "F.Cu" signal "TOP")
		(4 "In1.Cu" signal "L2GND")
		(6 "In2.Cu" signal "L3")
		(8 "In3.Cu" signal "L4GND")
		(10 "In4.Cu" signal "L5")
		(12 "In5.Cu" signal "L6GND")
		(14 "In6.Cu" signal "L7VCC")
		(16 "In7.Cu" signal "L8VCC")
		(18 "In8.Cu" signal "L9GND")
		(20 "In9.Cu" signal "L10")
		(22 "In10.Cu" signal "L11GND")
		(24 "In11.Cu" signal "L12")
		(26 "In12.Cu" signal "L13GND")
		(2 "B.Cu" signal "BOTTOM")
		(9 "F.Adhes" user "F.Adhesive")
		(11 "B.Adhes" user "B.Adhesive")
		(13 "F.Paste" user "Package Geometry/Pastemask Top")
		(15 "B.Paste" user "Package Geometry/Pastemask Bottom")
		(5 "F.SilkS" user "Ref Des/Silkscreen Top")
		(7 "B.SilkS" user "Ref Des/Silkscreen Bottom")
		(1 "F.Mask" user "Board Geometry/Soldermask Top")
		(3 "B.Mask" user "Board Geometry/Soldermask Bottom")
		(17 "Dwgs.User" user "User.Drawings")
		(19 "Cmts.User" user "User.Comments")
		(21 "Eco1.User" user "User.Eco1")
		(23 "Eco2.User" user "User.Eco2")
		(25 "Edge.Cuts" user "Board Geometry/Outline")
		(27 "Margin" user)
		(31 "F.CrtYd" user "Package Geometry/Place Bound Top")
		(29 "B.CrtYd" user "Package Geometry/Place Bound Bottom")
		(35 "F.Fab" user "Ref Des/Assembly Top")
		(33 "B.Fab" user "Ref Des/Assembly Bottom")
	)
	(footprint ""
		(layer "F.Cu")
		(at 192.532 -57.912 90)
		(property "Reference" "RT1"
			(at 1.01473 0.656336 0)
			(unlocked yes)
			(layer "F.SilkS")
			(effects
				(font
					(size 0.4064 0.254)
					(thickness 0.1524)
				)
			)
		)
		(property "Value" ""
			(at 0 0 90)
			(layer "F.Fab")
			(effects
				(font
					(size 1.27 1.27)
				)
			)
		)
		(duplicate_pad_numbers_are_jumpers no)
		(fp_poly
			(pts
				(xy -0.4953 -0.2032) (xy 0.4953 -0.2032) (xy 0.4953 1.6002) (xy -0.4953 1.6002)
			)
			(stroke
				(width 0)
				(type default)
			)
			(fill no)
			(layer "F.CrtYd")
		)
		(fp_line
			(start 0.4953 -0.2032)
			(end 0.4953 1.6002)
			(stroke
				(width 0.1)
				(type default)
			)
			(layer "F.Fab")
		)
		(fp_line
			(start -0.4953 -0.2032)
			(end 0.4953 -0.2032)
			(stroke
				(width 0.1)
				(type default)
			)
			(layer "F.Fab")
		)
		(fp_line
			(start 0.4953 1.6002)
			(end -0.4953 1.6002)
			(stroke
				(width 0.1)
				(type default)
			)
			(layer "F.Fab")
		)
		(fp_line
			(start -0.4953 1.6002)
			(end -0.4953 -0.2032)
			(stroke
				(width 0.1)
				(type default)
			)
			(layer "F.Fab")
		)
		(pad "1" smd rect
			(at 0 0 90)
			(size 0.762 0.889)
			(layers "F.Cu" "F.Mask" "F.Paste")
			(net "VR_PVCCIN_CPU0_PH1_BOOT")
		)
		(pad "2" smd rect
			(at 0 1.397 90)
			(size 0.762 0.889)
			(layers "F.Cu" "F.Mask" "F.Paste")
			(net "VR_PVCCIN_CPU0_PH1_BOOT_R")
		)
		(zone
			(layer "F.Cu")
			(hatch none 0.5)
			(connect_pads
				(clearance 0)
			)
			(min_thickness 0.25)
			(keepout
				(tracks allowed)
				(vias not_allowed)
				(pads allowed)
				(copperpour not_allowed)
				(footprints allowed)
			)
			(placement
				(enabled no)
				(sheetname "")
			)
			(fill
				(thermal_gap 0.5)
				(thermal_bridge_width 0.5)
				(island_removal_mode 0)
			)
			(polygon
				(pts
					(xy 193.4845 -58.293) (xy 192.9765 -58.293) (xy 192.9765 -57.531) (xy 193.4845 -57.531)
				)
			)
		)
		(zone
			(layer "F.Cu")
			(hatch none 0.5)
			(connect_pads
				(clearance 0)
			)
			(min_thickness 0.25)
			(keepout
				(tracks not_allowed)
				(vias allowed)
				(pads allowed)
				(copperpour not_allowed)
				(footprints allowed)
			)
			(placement
				(enabled no)
				(sheetname "")
			)
			(fill
				(thermal_gap 0.5)
				(thermal_bridge_width 0.5)
				(island_removal_mode 0)
			)
			(polygon
				(pts
					(xy 193.4845 -57.531) (xy 193.4845 -58.293) (xy 192.9765 -58.293) (xy 192.9765 -57.531)
				)
			)
		)
	)
	(footprint ""
		(layer "F.Cu")
		(at 362.36656 -142.045182 -90)
		(property "Reference" "RF17"
			(at -0.8382 -0.67818 270)
			(unlocked yes)
			(layer "F.SilkS")
			(effects
				(font
					(size 0.4064 0.254)
					(thickness 0.1524)
				)
				(justify left)
			)
		)
		(property "Value" ""
			(at 0 0 270)
			(layer "F.Fab")
			(effects
				(font
					(size 1.27 1.27)
				)
			)
		)
		(duplicate_pad_numbers_are_jumpers no)
		(fp_poly
			(pts
				(xy -0.2794 -0.1016) (xy 0.2794 -0.1016) (xy 0.2794 0.9906) (xy -0.2794 0.9906)
			)
			(stroke
				(width 0)
				(type default)
			)
			(fill no)
			(layer "F.CrtYd")
		)
		(fp_line
			(start -0.2794 0.9906)
			(end 0.2794 0.9906)
			(stroke
				(width 0.1)
				(type default)
			)
			(layer "F.Fab")
		)
		(fp_line
			(start 0.2794 0.9906)
			(end 0.2794 -0.1016)
			(stroke
				(width 0.1)
				(type default)
			)
			(layer "F.Fab")
		)
		(fp_line
			(start -0.2794 -0.1016)
			(end -0.2794 0.9906)
			(stroke
				(width 0.1)
				(type default)
			)
			(layer "F.Fab")
		)
		(fp_line
			(start 0.2794 -0.1016)
			(end -0.2794 -0.1016)
			(stroke
				(width 0.1)
				(type default)
			)
			(layer "F.Fab")
		)
		(pad "1" smd rect
			(at 0 0 270)
			(size 0.508 0.508)
			(layers "F.Cu" "F.Mask" "F.Paste")
			(net "VR_PVDDQ_DEF_AIREF1")
		)
		(pad "2" smd rect
			(at 0 0.889 270)
			(size 0.508 0.508)
			(layers "F.Cu" "F.Mask" "F.Paste")
			(net "ISENSE_PVDDQ_DEF_PH1_IMON")
		)
		(zone
			(layer "F.Cu")
			(hatch none 0.5)
			(connect_pads
				(clearance 0)
			)
			(min_thickness 0.25)
			(keepout
				(tracks not_allowed)
				(vias allowed)
				(pads allowed)
				(copperpour not_allowed)
				(footprints allowed)
			)
			(placement
				(enabled no)
				(sheetname "")
			)
			(fill
				(thermal_gap 0.5)
				(thermal_bridge_width 0.5)
				(island_removal_mode 0)
			)
			(polygon
				(pts
					(xy 361.73156 -142.299182) (xy 361.73156 -141.791182) (xy 362.11256 -141.791182) (xy 362.11256 -142.299182)
				)
			)
		)
		(zone
			(layer "F.Cu")
			(hatch none 0.5)
			(connect_pads
				(clearance 0)
			)
			(min_thickness 0.25)
			(keepout
				(tracks allowed)
				(vias not_allowed)
				(pads allowed)
				(copperpour not_allowed)
				(footprints allowed)
			)
			(placement
				(enabled no)
				(sheetname "")
			)
			(fill
				(thermal_gap 0.5)
				(thermal_bridge_width 0.5)
				(island_removal_mode 0)
			)
			(polygon
				(pts
					(xy 362.11256 -142.299182) (xy 362.11256 -141.791182) (xy 361.73156 -141.791182) (xy 361.73156 -142.299182)
				)
			)
		)
	)
	(footprint ""
		(layer "F.Cu")
		(at 101.92004 -77.636116)
		(property "Reference" "C2D26"
			(at 0 0 0)
			(layer "F.SilkS")
			(hide yes)
			(effects
				(font
					(size 1.27 1.27)
				)
			)
		)
		(property "Value" ""
			(at 0 0 0)
			(layer "F.Fab")
			(effects
				(font
					(size 1.27 1.27)
				)
			)
		)
		(duplicate_pad_numbers_are_jumpers no)
		(fp_poly
			(pts
				(xy -0.4953 -0.2032) (xy 0.4953 -0.2032) (xy 0.4953 1.6002) (xy -0.4953 1.6002)
			)
			(stroke
				(width 0)
				(type default)
			)
			(fill no)
			(layer "F.CrtYd")
		)
		(fp_line
			(start -0.4953 -0.2032)
			(end 0.4953 -0.2032)
			(stroke
				(width 0.1)
				(type default)
			)
			(layer "F.Fab")
		)
		(fp_line
			(start -0.4953 1.6002)
			(end -0.4953 -0.2032)
			(stroke
				(width 0.1)
				(type default)
			)
			(layer "F.Fab")
		)
		(fp_line
			(start 0.4953 -0.2032)
			(end 0.4953 1.6002)
			(stroke
				(width 0.1)
				(type default)
			)
			(layer "F.Fab")
		)
		(fp_line
			(start 0.4953 1.6002)
			(end -0.4953 1.6002)
			(stroke
				(width 0.1)
				(type default)
			)
			(layer "F.Fab")
		)
		(pad "1" smd rect
			(at 0 0)
			(size 0.762 0.889)
			(layers "F.Cu" "F.Mask" "F.Paste")
			(net "PVCCIN_CPU1")
		)
		(pad "2" smd rect
			(at 0 1.397)
			(size 0.762 0.889)
			(layers "F.Cu" "F.Mask" "F.Paste")
			(net "GND")
		)
		(zone
			(layer "F.Cu")
			(hatch none 0.5)
			(connect_pads
				(clearance 0)
			)
			(min_thickness 0.25)
			(keepout
				(tracks not_allowed)
				(vias allowed)
				(pads allowed)
				(copperpour not_allowed)
				(footprints allowed)
			)
			(placement
				(enabled no)
				(sheetname "")
			)
			(fill
				(thermal_gap 0.5)
				(thermal_bridge_width 0.5)
				(island_removal_mode 0)
			)
			(polygon
				(pts
					(xy 101.53904 -77.191616) (xy 102.30104 -77.191616) (xy 102.30104 -76.683616) (xy 101.53904 -76.683616)
				)
			)
		)
	)
)
